(kicad_pcb
	(version 20260206)
	(generator "pcbnew")
	(generator_version "10.0")
	(general
		(thickness 1.6)
		(legacy_teardrops no)
	)
	(paper "A4")
	(title_block
		(title "01162023_DA0F0TEBIF0_F0T_Expander_BD_F_brd_V02_OCP.brd")
		(comment 1 "Grand Teton / footprint 5329 of 9728 (J27), pads 110-179 of 179")
	)
	(layers
		(0 "F.Cu" signal "TOP")
		(4 "In1.Cu" signal "GND")
		(6 "In2.Cu" signal "VCC")
		(8 "In3.Cu" signal "VCC1")
		(10 "In4.Cu" signal "GND1")
		(12 "In5.Cu" signal "IN1")
		(14 "In6.Cu" signal "GND2")
		(16 "In7.Cu" signal "IN2")
		(18 "In8.Cu" signal "GND3")
		(20 "In9.Cu" signal "IN3")
		(22 "In10.Cu" signal "GND4")
		(24 "In11.Cu" signal "IN4")
		(26 "In12.Cu" signal "GND5")
		(28 "In13.Cu" signal "IN5")
		(30 "In14.Cu" signal "GND6")
		(32 "In15.Cu" signal "IN6")
		(34 "In16.Cu" signal "GND7")
		(2 "B.Cu" signal "BOTTOM")
		(9 "F.Adhes" user "F.Adhesive")
		(11 "B.Adhes" user "B.Adhesive")
		(13 "F.Paste" user "Package Geometry/Pastemask Top")
		(15 "B.Paste" user "Package Geometry/Pastemask Bottom")
		(5 "F.SilkS" user "Ref Des/Silkscreen Top")
		(7 "B.SilkS" user "Ref Des/Silkscreen Bottom")
		(1 "F.Mask" user "Board Geometry/Soldermask Top")
		(3 "B.Mask" user "Board Geometry/Soldermask Bottom")
		(17 "Dwgs.User" user "User.Drawings")
		(19 "Cmts.User" user "User.Comments")
		(21 "Eco1.User" user "User.Eco1")
		(23 "Eco2.User" user "User.Eco2")
		(25 "Edge.Cuts" user "Board Geometry/Outline")
		(27 "Margin" user)
		(31 "F.CrtYd" user "Package Geometry/Place Bound Top")
		(29 "B.CrtYd" user "Package Geometry/Place Bound Bottom")
		(35 "F.Fab" user "Ref Des/Assembly Top")
		(33 "B.Fab" user "Ref Des/Assembly Bottom")
	)
	(footprint ""
		(layer "F.Cu")
		(at 420.280084 -127.700024 180)
		(property "Reference" "J27"
			(at 5.446014 -34.532824 90)
			(unlocked yes)
			(layer "F.SilkS")
			(effects
				(font
					(size 0.7874 0.5842)
					(thickness 0.1524)
				)
				(justify left)
			)
		)
		(property "Value" ""
			(at 0 0 180)
			(layer "F.Fab")
			(effects
				(font
					(size 1.27 1.27)
				)
			)
		)
		(duplicate_pad_numbers_are_jumpers no)
		(pad "B38" smd rect
			(at -1.27762 7.14502 90)
			(size 0.3556 1.2192)
			(layers "F.Cu" "F.Mask" "F.Paste")
			(net "GND")
		)
		(pad "B39" smd rect
			(at -1.27762 7.744968 90)
			(size 0.3556 1.2192)
			(layers "F.Cu" "F.Mask" "F.Paste")
			(net "P5E_PEX3_STN0_TX_C_DN<7>")
		)
		(pad "B40" smd rect
			(at -1.27762 8.344916 90)
			(size 0.3556 1.2192)
			(layers "F.Cu" "F.Mask" "F.Paste")
			(net "P5E_PEX3_STN0_TX_C_DP<7>")
		)
		(pad "B41" smd rect
			(at -1.27762 8.945118 90)
			(size 0.3556 1.2192)
			(layers "F.Cu" "F.Mask" "F.Paste")
			(net "GND")
		)
		(pad "B42" smd rect
			(at -1.27762 9.545066 90)
			(size 0.3556 1.2192)
			(layers "F.Cu" "F.Mask" "F.Paste")
			(net "PRSNTB0_NIC7_N")
		)
		(pad "B43" smd rect
			(at -1.27762 14.454886 90)
			(size 0.3556 1.2192)
			(layers "F.Cu" "F.Mask" "F.Paste")
			(net "GND")
		)
		(pad "B44" smd rect
			(at -1.27762 15.055088 90)
			(size 0.3556 1.2192)
			(layers "F.Cu" "F.Mask" "F.Paste")
			(net "P5E_PEX3_STN0_TX_C_DN<8>")
		)
		(pad "B45" smd rect
			(at -1.27762 15.655036 90)
			(size 0.3556 1.2192)
			(layers "F.Cu" "F.Mask" "F.Paste")
			(net "P5E_PEX3_STN0_TX_C_DP<8>")
		)
		(pad "B46" smd rect
			(at -1.27762 16.254984 90)
			(size 0.3556 1.2192)
			(layers "F.Cu" "F.Mask" "F.Paste")
			(net "GND")
		)
		(pad "B47" smd rect
			(at -1.27762 16.854932 90)
			(size 0.3556 1.2192)
			(layers "F.Cu" "F.Mask" "F.Paste")
			(net "P5E_PEX3_STN0_TX_C_DN<9>")
		)
		(pad "B48" smd rect
			(at -1.27762 17.45488 90)
			(size 0.3556 1.2192)
			(layers "F.Cu" "F.Mask" "F.Paste")
			(net "P5E_PEX3_STN0_TX_C_DP<9>")
		)
		(pad "B49" smd rect
			(at -1.27762 18.055082 90)
			(size 0.3556 1.2192)
			(layers "F.Cu" "F.Mask" "F.Paste")
			(net "GND")
		)
		(pad "B50" smd rect
			(at -1.27762 18.65503 90)
			(size 0.3556 1.2192)
			(layers "F.Cu" "F.Mask" "F.Paste")
			(net "P5E_PEX3_STN0_TX_C_DN<10>")
		)
		(pad "B51" smd rect
			(at -1.27762 19.254978 90)
			(size 0.3556 1.2192)
			(layers "F.Cu" "F.Mask" "F.Paste")
			(net "P5E_PEX3_STN0_TX_C_DP<10>")
		)
		(pad "B52" smd rect
			(at -1.27762 19.854926 90)
			(size 0.3556 1.2192)
			(layers "F.Cu" "F.Mask" "F.Paste")
			(net "GND")
		)
		(pad "B53" smd rect
			(at -1.27762 20.455128 90)
			(size 0.3556 1.2192)
			(layers "F.Cu" "F.Mask" "F.Paste")
			(net "P5E_PEX3_STN0_TX_C_DN<11>")
		)
		(pad "B54" smd rect
			(at -1.27762 21.055076 90)
			(size 0.3556 1.2192)
			(layers "F.Cu" "F.Mask" "F.Paste")
			(net "P5E_PEX3_STN0_TX_C_DP<11>")
		)
		(pad "B55" smd rect
			(at -1.27762 21.655024 90)
			(size 0.3556 1.2192)
			(layers "F.Cu" "F.Mask" "F.Paste")
			(net "GND")
		)
		(pad "B56" smd rect
			(at -1.27762 22.254972 90)
			(size 0.3556 1.2192)
			(layers "F.Cu" "F.Mask" "F.Paste")
			(net "P5E_PEX3_STN0_TX_C_DP<12>")
		)
		(pad "B57" smd rect
			(at -1.27762 22.85492 90)
			(size 0.3556 1.2192)
			(layers "F.Cu" "F.Mask" "F.Paste")
			(net "P5E_PEX3_STN0_TX_C_DN<12>")
		)
		(pad "B58" smd rect
			(at -1.27762 23.455122 90)
			(size 0.3556 1.2192)
			(layers "F.Cu" "F.Mask" "F.Paste")
			(net "GND")
		)
		(pad "B59" smd rect
			(at -1.27762 24.05507 90)
			(size 0.3556 1.2192)
			(layers "F.Cu" "F.Mask" "F.Paste")
			(net "P5E_PEX3_STN0_TX_C_DN<13>")
		)
		(pad "B60" smd rect
			(at -1.27762 24.655018 90)
			(size 0.3556 1.2192)
			(layers "F.Cu" "F.Mask" "F.Paste")
			(net "P5E_PEX3_STN0_TX_C_DP<13>")
		)
		(pad "B61" smd rect
			(at -1.27762 25.254966 90)
			(size 0.3556 1.2192)
			(layers "F.Cu" "F.Mask" "F.Paste")
			(net "GND")
		)
		(pad "B62" smd rect
			(at -1.27762 25.854914 90)
			(size 0.3556 1.2192)
			(layers "F.Cu" "F.Mask" "F.Paste")
			(net "P5E_PEX3_STN0_TX_C_DP<14>")
		)
		(pad "B63" smd rect
			(at -1.27762 26.455116 90)
			(size 0.3556 1.2192)
			(layers "F.Cu" "F.Mask" "F.Paste")
			(net "P5E_PEX3_STN0_TX_C_DN<14>")
		)
		(pad "B64" smd rect
			(at -1.27762 27.055064 90)
			(size 0.3556 1.2192)
			(layers "F.Cu" "F.Mask" "F.Paste")
			(net "GND")
		)
		(pad "B65" smd rect
			(at -1.27762 27.655012 90)
			(size 0.3556 1.2192)
			(layers "F.Cu" "F.Mask" "F.Paste")
			(net "P5E_PEX3_STN0_TX_C_DN<15>")
		)
		(pad "B66" smd rect
			(at -1.27762 28.25496 90)
			(size 0.3556 1.2192)
			(layers "F.Cu" "F.Mask" "F.Paste")
			(net "P5E_PEX3_STN0_TX_C_DP<15>")
		)
		(pad "B67" smd rect
			(at -1.27762 28.854908 90)
			(size 0.3556 1.2192)
			(layers "F.Cu" "F.Mask" "F.Paste")
			(net "GND")
		)
		(pad "B68" smd rect
			(at -1.27762 29.45511 90)
			(size 0.3556 1.2192)
			(layers "F.Cu" "F.Mask" "F.Paste")
			(net "Net_2672")
		)
		(pad "B69" smd rect
			(at -1.27762 30.055058 90)
			(size 0.3556 1.2192)
			(layers "F.Cu" "F.Mask" "F.Paste")
			(net "Net_2673")
		)
		(pad "B70" smd rect
			(at -1.27762 30.655006 90)
			(size 0.3556 1.2192)
			(layers "F.Cu" "F.Mask" "F.Paste")
			(net "PRSNTB3_NIC7_N")
		)
		(pad "G1" thru_hole oval
			(at 1.022604 -34.034984 90)
			(size 1.6256 3.4798)
			(drill oval 1.1176 2.4638)
			(layers "*.Cu" "*.Mask")
			(remove_unused_layers no)
			(net "GND")
			(clearance 0.127)
			(thermal_gap 0.127)
		)
		(pad "G2" thru_hole oval
			(at 1.022604 -20.625054 90)
			(size 1.6256 3.4798)
			(drill oval 1.1176 2.4638)
			(layers "*.Cu" "*.Mask")
			(remove_unused_layers no)
			(net "GND")
			(clearance 0.127)
			(thermal_gap 0.127)
		)
		(pad "G3" thru_hole oval
			(at 1.022604 -0.255016 90)
			(size 1.6256 3.4798)
			(drill oval 1.1176 2.4638)
			(layers "*.Cu" "*.Mask")
			(remove_unused_layers no)
			(net "GND")
			(clearance 0.127)
			(thermal_gap 0.127)
		)
		(pad "G4" thru_hole oval
			(at 1.022604 12.005056 90)
			(size 1.6256 3.4798)
			(drill oval 1.1176 2.4638)
			(layers "*.Cu" "*.Mask")
			(remove_unused_layers no)
			(net "GND")
			(clearance 0.127)
			(thermal_gap 0.127)
		)
		(pad "G5" thru_hole oval
			(at 1.022604 34.034984 90)
			(size 1.5748 3.4798)
			(drill oval 1.1176 2.4638)
			(layers "*.Cu" "*.Mask")
			(remove_unused_layers no)
			(net "GND")
			(clearance 0.1524)
			(thermal_gap 0.1524)
		)
		(pad "G6" thru_hole circle
			(at -3.16738 -20.625054 180)
			(size 1.6256 1.6256)
			(drill 1.1176)
			(layers "*.Cu" "*.Mask")
			(remove_unused_layers no)
			(net "GND")
			(clearance 0)
		)
		(pad "G7" thru_hole circle
			(at -3.16738 12.005056 180)
			(size 1.6256 1.6256)
			(drill 1.1176)
			(layers "*.Cu" "*.Mask")
			(remove_unused_layers no)
			(net "GND")
			(clearance 0)
		)
		(pad "G8" thru_hole circle
			(at 4.20243 -20.625054 180)
			(size 1.6256 1.6256)
			(drill 1.1176)
			(layers "*.Cu" "*.Mask")
			(remove_unused_layers no)
			(net "GND")
			(clearance 0)
		)
		(pad "G9" thru_hole circle
			(at 4.20243 12.005056 180)
			(size 1.6256 1.6256)
			(drill 1.1176)
			(layers "*.Cu" "*.Mask")
			(remove_unused_layers no)
			(net "GND")
			(clearance 0)
		)
		(pad "OA1" smd rect
			(at 3.322574 -30.660086 90)
			(size 0.3556 1.2192)
			(layers "F.Cu" "F.Mask" "F.Paste")
			(net "RST_NIC7_PERST2_R_N")
		)
		(pad "OA2" smd rect
			(at 3.322574 -30.059884 90)
			(size 0.3556 1.2192)
			(layers "F.Cu" "F.Mask" "F.Paste")
			(net "RST_NIC7_PERST3_R_N")
		)
		(pad "OA3" smd rect
			(at 3.322574 -29.459936 90)
			(size 0.3556 1.2192)
			(layers "F.Cu" "F.Mask" "F.Paste")
			(net "Net_2676")
		)
		(pad "OA4" smd rect
			(at 3.322574 -28.859988 90)
			(size 0.3556 1.2192)
			(layers "F.Cu" "F.Mask" "F.Paste")
			(net "NIC7_RBT_ARB_IN")
		)
		(pad "OA5" smd rect
			(at 3.322574 -28.26004 90)
			(size 0.3556 1.2192)
			(layers "F.Cu" "F.Mask" "F.Paste")
			(net "NIC7_RBT_ARB_OUT")
		)
		(pad "OA6" smd rect
			(at 3.322574 -27.660092 90)
			(size 0.3556 1.2192)
			(layers "F.Cu" "F.Mask" "F.Paste")
			(net "NIC7_SLOT_ID1")
		)
		(pad "OA7" smd rect
			(at 3.322574 -27.05989 90)
			(size 0.3556 1.2192)
			(layers "F.Cu" "F.Mask" "F.Paste")
			(net "NCSI_NIC7_TX_EN")
		)
		(pad "OA8" smd rect
			(at 3.322574 -26.459942 90)
			(size 0.3556 1.2192)
			(layers "F.Cu" "F.Mask" "F.Paste")
			(net "NCSI_NIC7_TXD1")
		)
		(pad "OA9" smd rect
			(at 3.322574 -25.859994 90)
			(size 0.3556 1.2192)
			(layers "F.Cu" "F.Mask" "F.Paste")
			(net "NCSI_NIC7_TXD0")
		)
		(pad "OA10" smd rect
			(at 3.322574 -25.260046 90)
			(size 0.3556 1.2192)
			(layers "F.Cu" "F.Mask" "F.Paste")
			(net "GND")
		)
		(pad "OA11" smd rect
			(at 3.322574 -24.660098 90)
			(size 0.3556 1.2192)
			(layers "F.Cu" "F.Mask" "F.Paste")
			(net "Net_2668")
		)
		(pad "OA12" smd rect
			(at 3.322574 -24.059896 90)
			(size 0.3556 1.2192)
			(layers "F.Cu" "F.Mask" "F.Paste")
			(net "Net_2671")
		)
		(pad "OA13" smd rect
			(at 3.322574 -23.459948 90)
			(size 0.3556 1.2192)
			(layers "F.Cu" "F.Mask" "F.Paste")
			(net "GND")
		)
		(pad "OA14" smd rect
			(at 3.322574 -22.86 90)
			(size 0.3556 1.2192)
			(layers "F.Cu" "F.Mask" "F.Paste")
			(net "CLK_50M_NIC7_RBT_REF")
		)
		(pad "OB1" smd rect
			(at -1.27762 -30.660086 90)
			(size 0.3556 1.2192)
			(layers "F.Cu" "F.Mask" "F.Paste")
			(net "PWRGD_NIC7_PWR_GOOD")
		)
		(pad "OB2" smd rect
			(at -1.27762 -30.059884 90)
			(size 0.3556 1.2192)
			(layers "F.Cu" "F.Mask" "F.Paste")
			(net "NIC7_MAIN_PWR_EN_R")
		)
		(pad "OB3" smd rect
			(at -1.27762 -29.459936 90)
			(size 0.3556 1.2192)
			(layers "F.Cu" "F.Mask" "F.Paste")
			(net "NIC7_LD_N")
		)
		(pad "OB4" smd rect
			(at -1.27762 -28.859988 90)
			(size 0.3556 1.2192)
			(layers "F.Cu" "F.Mask" "F.Paste")
			(net "NIC7_DATA_IN")
		)
		(pad "OB5" smd rect
			(at -1.27762 -28.26004 90)
			(size 0.3556 1.2192)
			(layers "F.Cu" "F.Mask" "F.Paste")
			(net "NIC7_DATA_OUT")
		)
		(pad "OB6" smd rect
			(at -1.27762 -27.660092 90)
			(size 0.3556 1.2192)
			(layers "F.Cu" "F.Mask" "F.Paste")
			(net "NIC7_CLK")
		)
		(pad "OB7" smd rect
			(at -1.27762 -27.05989 90)
			(size 0.3556 1.2192)
			(layers "F.Cu" "F.Mask" "F.Paste")
			(net "NIC7_SLOT_ID0")
		)
		(pad "OB8" smd rect
			(at -1.27762 -26.459942 90)
			(size 0.3556 1.2192)
			(layers "F.Cu" "F.Mask" "F.Paste")
			(net "NCSI_NIC7_RXD1")
		)
		(pad "OB9" smd rect
			(at -1.27762 -25.859994 90)
			(size 0.3556 1.2192)
			(layers "F.Cu" "F.Mask" "F.Paste")
			(net "NCSI_NIC7_RXD0")
		)
		(pad "OB10" smd rect
			(at -1.27762 -25.260046 90)
			(size 0.3556 1.2192)
			(layers "F.Cu" "F.Mask" "F.Paste")
			(net "GND")
		)
		(pad "OB11" smd rect
			(at -1.27762 -24.660098 90)
			(size 0.3556 1.2192)
			(layers "F.Cu" "F.Mask" "F.Paste")
			(net "Net_2667")
		)
		(pad "OB12" smd rect
			(at -1.27762 -24.059896 90)
			(size 0.3556 1.2192)
			(layers "F.Cu" "F.Mask" "F.Paste")
			(net "Net_2670")
		)
		(pad "OB13" smd rect
			(at -1.27762 -23.459948 90)
			(size 0.3556 1.2192)
			(layers "F.Cu" "F.Mask" "F.Paste")
			(net "GND")
		)
		(pad "OB14" smd rect
			(at -1.27762 -22.86 90)
			(size 0.3556 1.2192)
			(layers "F.Cu" "F.Mask" "F.Paste")
			(net "NCSI_NIC7_CRS_DV")
		)
	)
)
